(kicad_pcb
	(version 20260206)
	(generator "pcbnew")
	(generator_version "10.0")
	(general
		(thickness 1.6)
		(legacy_teardrops no)
	)
	(paper "A4")
	(title_block
		(title "04192023_DAF0TMB3IC0_F0TG_MB_C_brd_V02_OCP.brd")
		(comment 1 "Grand Teton / footprints 6610-6615 of 8354")
	)
	(layers
		(0 "F.Cu" signal "TOP")
		(4 "In1.Cu" signal "GND")
		(6 "In2.Cu" signal "IN1")
		(8 "In3.Cu" signal "GND1")
		(10 "In4.Cu" signal "IN2")
		(12 "In5.Cu" signal "GND2")
		(14 "In6.Cu" signal "IN3")
		(16 "In7.Cu" signal "GND3")
		(18 "In8.Cu" signal "VCC")
		(20 "In9.Cu" signal "VCC1")
		(22 "In10.Cu" signal "GND4")
		(24 "In11.Cu" signal "IN4")
		(26 "In12.Cu" signal "GND5")
		(28 "In13.Cu" signal "IN5")
		(30 "In14.Cu" signal "GND6")
		(32 "In15.Cu" signal "IN6")
		(34 "In16.Cu" signal "GND7")
		(2 "B.Cu" signal "BOTTOM")
		(9 "F.Adhes" user "F.Adhesive")
		(11 "B.Adhes" user "B.Adhesive")
		(13 "F.Paste" user "Package Geometry/Pastemask Top")
		(15 "B.Paste" user "Package Geometry/Pastemask Bottom")
		(5 "F.SilkS" user "Ref Des/Silkscreen Top")
		(7 "B.SilkS" user "Ref Des/Silkscreen Bottom")
		(1 "F.Mask" user "Board Geometry/Soldermask Top")
		(3 "B.Mask" user "Board Geometry/Soldermask Bottom")
		(17 "Dwgs.User" user "User.Drawings")
		(19 "Cmts.User" user "User.Comments")
		(21 "Eco1.User" user "User.Eco1")
		(23 "Eco2.User" user "User.Eco2")
		(25 "Edge.Cuts" user "Board Geometry/Outline")
		(27 "Margin" user)
		(31 "F.CrtYd" user "Package Geometry/Place Bound Top")
		(29 "B.CrtYd" user "Package Geometry/Place Bound Bottom")
		(35 "F.Fab" user "Ref Des/Assembly Top")
		(33 "B.Fab" user "Ref Des/Assembly Bottom")
	)
	(footprint ""
		(layer "B.Cu")
		(at 117.895624 -257.455416)
		(property "Reference" "C2464"
			(at 0 0 0)
			(layer "B.SilkS")
			(hide yes)
			(effects
				(font
					(size 1.27 1.27)
				)
				(justify mirror)
			)
		)
		(property "Value" ""
			(at 0 0 0)
			(layer "B.Fab")
			(effects
				(font
					(size 1.27 1.27)
				)
				(justify mirror)
			)
		)
		(duplicate_pad_numbers_are_jumpers no)
		(fp_line
			(start -0.7874 -0.4064)
			(end -0.7874 0.4064)
			(stroke
				(width 0.1524)
				(type default)
			)
			(layer "B.SilkS")
		)
		(fp_line
			(start -0.7874 0.4064)
			(end 0.7874 0.4064)
			(stroke
				(width 0.1524)
				(type default)
			)
			(layer "B.SilkS")
		)
		(fp_line
			(start 0.7874 -0.4064)
			(end -0.7874 -0.4064)
			(stroke
				(width 0.1524)
				(type default)
			)
			(layer "B.SilkS")
		)
		(fp_line
			(start 0.7874 0.4064)
			(end 0.7874 -0.4064)
			(stroke
				(width 0.1524)
				(type default)
			)
			(layer "B.SilkS")
		)
		(fp_line
			(start -0.67945 -0.3048)
			(end -0.67945 0.3048)
			(stroke
				(width 0.1)
				(type default)
			)
			(layer "B.Fab")
		)
		(fp_line
			(start -0.67945 0.3048)
			(end -0.120396 0.3048)
			(stroke
				(width 0.1)
				(type default)
			)
			(layer "B.Fab")
		)
		(fp_line
			(start -0.12065 -0.3048)
			(end -0.67945 -0.3048)
			(stroke
				(width 0.1)
				(type default)
			)
			(layer "B.Fab")
		)
		(fp_line
			(start -0.12065 -0.2794)
			(end -0.12065 -0.3048)
			(stroke
				(width 0.1)
				(type default)
			)
			(layer "B.Fab")
		)
		(fp_line
			(start -0.120396 0.2794)
			(end 0.12065 0.2794)
			(stroke
				(width 0.1)
				(type default)
			)
			(layer "B.Fab")
		)
		(fp_line
			(start -0.120396 0.3048)
			(end -0.120396 0.2794)
			(stroke
				(width 0.1)
				(type default)
			)
			(layer "B.Fab")
		)
		(fp_line
			(start 0.12065 -0.305054)
			(end 0.12065 -0.2794)
			(stroke
				(width 0.1)
				(type default)
			)
			(layer "B.Fab")
		)
		(fp_line
			(start 0.12065 -0.2794)
			(end -0.12065 -0.2794)
			(stroke
				(width 0.1)
				(type default)
			)
			(layer "B.Fab")
		)
		(fp_line
			(start 0.12065 0.2794)
			(end 0.12065 0.3048)
			(stroke
				(width 0.1)
				(type default)
			)
			(layer "B.Fab")
		)
		(fp_line
			(start 0.12065 0.3048)
			(end 0.67945 0.3048)
			(stroke
				(width 0.1)
				(type default)
			)
			(layer "B.Fab")
		)
		(fp_line
			(start 0.67945 -0.305054)
			(end 0.12065 -0.305054)
			(stroke
				(width 0.1)
				(type default)
			)
			(layer "B.Fab")
		)
		(fp_line
			(start 0.67945 0.3048)
			(end 0.67945 -0.305054)
			(stroke
				(width 0.1)
				(type default)
			)
			(layer "B.Fab")
		)
		(pad "1" smd circle
			(at 0.40005 0 180)
			(size 0 0)
			(layers "B.Cu" "B.Mask" "B.Paste")
			(net "PVDDCR_SOC_P1")
		)
		(pad "2" smd circle
			(at -0.40005 0 180)
			(size 0 0)
			(layers "B.Cu" "B.Mask" "B.Paste")
			(net "GND")
		)
	)
	(footprint ""
		(layer "B.Cu")
		(at 369.392454 -267.498576)
		(property "Reference" "C2243"
			(at 0 0 0)
			(layer "B.SilkS")
			(hide yes)
			(effects
				(font
					(size 1.27 1.27)
				)
				(justify mirror)
			)
		)
		(property "Value" ""
			(at 0 0 0)
			(layer "B.Fab")
			(effects
				(font
					(size 1.27 1.27)
				)
				(justify mirror)
			)
		)
		(duplicate_pad_numbers_are_jumpers no)
		(fp_line
			(start -0.7874 -0.4064)
			(end -0.7874 0.4064)
			(stroke
				(width 0.1524)
				(type default)
			)
			(layer "B.SilkS")
		)
		(fp_line
			(start -0.7874 0.4064)
			(end 0.7874 0.4064)
			(stroke
				(width 0.1524)
				(type default)
			)
			(layer "B.SilkS")
		)
		(fp_line
			(start 0.7874 -0.4064)
			(end -0.7874 -0.4064)
			(stroke
				(width 0.1524)
				(type default)
			)
			(layer "B.SilkS")
		)
		(fp_line
			(start 0.7874 0.4064)
			(end 0.7874 -0.4064)
			(stroke
				(width 0.1524)
				(type default)
			)
			(layer "B.SilkS")
		)
		(fp_line
			(start -0.67945 -0.3048)
			(end -0.67945 0.3048)
			(stroke
				(width 0.1)
				(type default)
			)
			(layer "B.Fab")
		)
		(fp_line
			(start -0.67945 0.3048)
			(end -0.120396 0.3048)
			(stroke
				(width 0.1)
				(type default)
			)
			(layer "B.Fab")
		)
		(fp_line
			(start -0.12065 -0.3048)
			(end -0.67945 -0.3048)
			(stroke
				(width 0.1)
				(type default)
			)
			(layer "B.Fab")
		)
		(fp_line
			(start -0.12065 -0.2794)
			(end -0.12065 -0.3048)
			(stroke
				(width 0.1)
				(type default)
			)
			(layer "B.Fab")
		)
		(fp_line
			(start -0.120396 0.2794)
			(end 0.12065 0.2794)
			(stroke
				(width 0.1)
				(type default)
			)
			(layer "B.Fab")
		)
		(fp_line
			(start -0.120396 0.3048)
			(end -0.120396 0.2794)
			(stroke
				(width 0.1)
				(type default)
			)
			(layer "B.Fab")
		)
		(fp_line
			(start 0.12065 -0.305054)
			(end 0.12065 -0.2794)
			(stroke
				(width 0.1)
				(type default)
			)
			(layer "B.Fab")
		)
		(fp_line
			(start 0.12065 -0.2794)
			(end -0.12065 -0.2794)
			(stroke
				(width 0.1)
				(type default)
			)
			(layer "B.Fab")
		)
		(fp_line
			(start 0.12065 0.2794)
			(end 0.12065 0.3048)
			(stroke
				(width 0.1)
				(type default)
			)
			(layer "B.Fab")
		)
		(fp_line
			(start 0.12065 0.3048)
			(end 0.67945 0.3048)
			(stroke
				(width 0.1)
				(type default)
			)
			(layer "B.Fab")
		)
		(fp_line
			(start 0.67945 -0.305054)
			(end 0.12065 -0.305054)
			(stroke
				(width 0.1)
				(type default)
			)
			(layer "B.Fab")
		)
		(fp_line
			(start 0.67945 0.3048)
			(end 0.67945 -0.305054)
			(stroke
				(width 0.1)
				(type default)
			)
			(layer "B.Fab")
		)
		(pad "1" smd circle
			(at 0.40005 0 180)
			(size 0 0)
			(layers "B.Cu" "B.Mask" "B.Paste")
			(net "PVDDCR_CPU1_P0")
		)
		(pad "2" smd circle
			(at -0.40005 0 180)
			(size 0 0)
			(layers "B.Cu" "B.Mask" "B.Paste")
			(net "GND")
		)
	)
	(footprint ""
		(layer "B.Cu")
		(at 94.460314 -306.714652)
		(property "Reference" "R456"
			(at 0 0 0)
			(layer "B.SilkS")
			(hide yes)
			(effects
				(font
					(size 1.27 1.27)
				)
				(justify mirror)
			)
		)
		(property "Value" ""
			(at 0 0 0)
			(layer "B.Fab")
			(effects
				(font
					(size 1.27 1.27)
				)
				(justify mirror)
			)
		)
		(duplicate_pad_numbers_are_jumpers no)
		(fp_line
			(start -0.7874 -0.4064)
			(end -0.7874 0.4064)
			(stroke
				(width 0.1524)
				(type default)
			)
			(layer "B.SilkS")
		)
		(fp_line
			(start -0.7874 0.4064)
			(end 0.7874 0.4064)
			(stroke
				(width 0.1524)
				(type default)
			)
			(layer "B.SilkS")
		)
		(fp_line
			(start 0.7874 -0.4064)
			(end -0.7874 -0.4064)
			(stroke
				(width 0.1524)
				(type default)
			)
			(layer "B.SilkS")
		)
		(fp_line
			(start 0.7874 0.4064)
			(end 0.7874 -0.4064)
			(stroke
				(width 0.1524)
				(type default)
			)
			(layer "B.SilkS")
		)
		(fp_line
			(start -0.67945 -0.3048)
			(end -0.67945 0.3048)
			(stroke
				(width 0.1)
				(type default)
			)
			(layer "B.Fab")
		)
		(fp_line
			(start -0.67945 0.3048)
			(end -0.120396 0.3048)
			(stroke
				(width 0.1)
				(type default)
			)
			(layer "B.Fab")
		)
		(fp_line
			(start -0.12065 -0.3048)
			(end -0.67945 -0.3048)
			(stroke
				(width 0.1)
				(type default)
			)
			(layer "B.Fab")
		)
		(fp_line
			(start -0.12065 -0.2794)
			(end -0.12065 -0.3048)
			(stroke
				(width 0.1)
				(type default)
			)
			(layer "B.Fab")
		)
		(fp_line
			(start -0.120396 0.2794)
			(end 0.12065 0.2794)
			(stroke
				(width 0.1)
				(type default)
			)
			(layer "B.Fab")
		)
		(fp_line
			(start -0.120396 0.3048)
			(end -0.120396 0.2794)
			(stroke
				(width 0.1)
				(type default)
			)
			(layer "B.Fab")
		)
		(fp_line
			(start 0.12065 -0.305054)
			(end 0.12065 -0.2794)
			(stroke
				(width 0.1)
				(type default)
			)
			(layer "B.Fab")
		)
		(fp_line
			(start 0.12065 -0.2794)
			(end -0.12065 -0.2794)
			(stroke
				(width 0.1)
				(type default)
			)
			(layer "B.Fab")
		)
		(fp_line
			(start 0.12065 0.2794)
			(end 0.12065 0.3048)
			(stroke
				(width 0.1)
				(type default)
			)
			(layer "B.Fab")
		)
		(fp_line
			(start 0.12065 0.3048)
			(end 0.67945 0.3048)
			(stroke
				(width 0.1)
				(type default)
			)
			(layer "B.Fab")
		)
		(fp_line
			(start 0.67945 -0.305054)
			(end 0.12065 -0.305054)
			(stroke
				(width 0.1)
				(type default)
			)
			(layer "B.Fab")
		)
		(fp_line
			(start 0.67945 0.3048)
			(end 0.67945 -0.305054)
			(stroke
				(width 0.1)
				(type default)
			)
			(layer "B.Fab")
		)
		(pad "1" smd circle
			(at 0.40005 0 180)
			(size 0 0)
			(layers "B.Cu" "B.Mask" "B.Paste")
			(net "CPU1_PWRGD_OUT")
		)
		(pad "2" smd circle
			(at -0.40005 0 180)
			(size 0 0)
			(layers "B.Cu" "B.Mask" "B.Paste")
			(net "PVDD18_S5_P1")
		)
	)
	(footprint ""
		(layer "B.Cu")
		(at 377.839986 -214.523828 90)
		(property "Reference" "R9276"
			(at 0 0 90)
			(layer "B.SilkS")
			(hide yes)
			(effects
				(font
					(size 1.27 1.27)
				)
				(justify mirror)
			)
		)
		(property "Value" ""
			(at 0 0 90)
			(layer "B.Fab")
			(effects
				(font
					(size 1.27 1.27)
				)
				(justify mirror)
			)
		)
		(duplicate_pad_numbers_are_jumpers no)
		(fp_line
			(start 0.7874 -0.4064)
			(end -0.7874 -0.4064)
			(stroke
				(width 0.1524)
				(type default)
			)
			(layer "B.SilkS")
		)
		(fp_line
			(start -0.7874 -0.4064)
			(end -0.7874 0.086614)
			(stroke
				(width 0.1524)
				(type default)
			)
			(layer "B.SilkS")
		)
		(fp_line
			(start 0.7874 0.035814)
			(end 0.7874 -0.4064)
			(stroke
				(width 0.1524)
				(type default)
			)
			(layer "B.SilkS")
		)
		(fp_line
			(start -0.376428 0.4064)
			(end 0.360172 0.4064)
			(stroke
				(width 0.1524)
				(type default)
			)
			(layer "B.SilkS")
		)
		(fp_line
			(start 0.67945 -0.305054)
			(end 0.12065 -0.305054)
			(stroke
				(width 0.1)
				(type default)
			)
			(layer "B.Fab")
		)
		(fp_line
			(start 0.12065 -0.305054)
			(end 0.12065 -0.2794)
			(stroke
				(width 0.1)
				(type default)
			)
			(layer "B.Fab")
		)
		(fp_line
			(start -0.12065 -0.3048)
			(end -0.67945 -0.3048)
			(stroke
				(width 0.1)
				(type default)
			)
			(layer "B.Fab")
		)
		(fp_line
			(start -0.67945 -0.3048)
			(end -0.67945 0.3048)
			(stroke
				(width 0.1)
				(type default)
			)
			(layer "B.Fab")
		)
		(fp_line
			(start 0.12065 -0.2794)
			(end -0.12065 -0.2794)
			(stroke
				(width 0.1)
				(type default)
			)
			(layer "B.Fab")
		)
		(fp_line
			(start -0.12065 -0.2794)
			(end -0.12065 -0.3048)
			(stroke
				(width 0.1)
				(type default)
			)
			(layer "B.Fab")
		)
		(fp_line
			(start 0.12065 0.2794)
			(end 0.12065 0.3048)
			(stroke
				(width 0.1)
				(type default)
			)
			(layer "B.Fab")
		)
		(fp_line
			(start -0.120396 0.2794)
			(end 0.12065 0.2794)
			(stroke
				(width 0.1)
				(type default)
			)
			(layer "B.Fab")
		)
		(fp_line
			(start 0.67945 0.3048)
			(end 0.67945 -0.305054)
			(stroke
				(width 0.1)
				(type default)
			)
			(layer "B.Fab")
		)
		(fp_line
			(start 0.12065 0.3048)
			(end 0.67945 0.3048)
			(stroke
				(width 0.1)
				(type default)
			)
			(layer "B.Fab")
		)
		(fp_line
			(start -0.120396 0.3048)
			(end -0.120396 0.2794)
			(stroke
				(width 0.1)
				(type default)
			)
			(layer "B.Fab")
		)
		(fp_line
			(start -0.67945 0.3048)
			(end -0.120396 0.3048)
			(stroke
				(width 0.1)
				(type default)
			)
			(layer "B.Fab")
		)
		(pad "1" smd circle
			(at 0.40005 0 270)
			(size 0 0)
			(layers "B.Cu" "B.Mask" "B.Paste")
			(net "CLK_100M_CPU0_CLK05_R_DN")
		)
		(pad "2" smd circle
			(at -0.40005 0 270)
			(size 0 0)
			(layers "B.Cu" "B.Mask" "B.Paste")
			(net "CLK_100M_CPU0_CLK05_DN")
		)
	)
	(footprint ""
		(layer "B.Cu")
		(at 236.676692 -422.849548 90)
		(property "Reference" "C67"
			(at 0 0 90)
			(layer "B.SilkS")
			(hide yes)
			(effects
				(font
					(size 1.27 1.27)
				)
				(justify mirror)
			)
		)
		(property "Value" ""
			(at 0 0 90)
			(layer "B.Fab")
			(effects
				(font
					(size 1.27 1.27)
				)
				(justify mirror)
			)
		)
		(duplicate_pad_numbers_are_jumpers no)
		(fp_line
			(start 0.7874 -0.4064)
			(end -0.7874 -0.4064)
			(stroke
				(width 0.1524)
				(type default)
			)
			(layer "B.SilkS")
		)
		(fp_line
			(start -0.7874 -0.4064)
			(end -0.7874 0.4064)
			(stroke
				(width 0.1524)
				(type default)
			)
			(layer "B.SilkS")
		)
		(fp_line
			(start 0.7874 0.4064)
			(end 0.7874 -0.4064)
			(stroke
				(width 0.1524)
				(type default)
			)
			(layer "B.SilkS")
		)
		(fp_line
			(start -0.7874 0.4064)
			(end 0.7874 0.4064)
			(stroke
				(width 0.1524)
				(type default)
			)
			(layer "B.SilkS")
		)
		(fp_line
			(start 0.67945 -0.305054)
			(end 0.12065 -0.305054)
			(stroke
				(width 0.1)
				(type default)
			)
			(layer "B.Fab")
		)
		(fp_line
			(start 0.12065 -0.305054)
			(end 0.12065 -0.2794)
			(stroke
				(width 0.1)
				(type default)
			)
			(layer "B.Fab")
		)
		(fp_line
			(start -0.12065 -0.3048)
			(end -0.67945 -0.3048)
			(stroke
				(width 0.1)
				(type default)
			)
			(layer "B.Fab")
		)
		(fp_line
			(start -0.67945 -0.3048)
			(end -0.67945 0.3048)
			(stroke
				(width 0.1)
				(type default)
			)
			(layer "B.Fab")
		)
		(fp_line
			(start 0.12065 -0.2794)
			(end -0.12065 -0.2794)
			(stroke
				(width 0.1)
				(type default)
			)
			(layer "B.Fab")
		)
		(fp_line
			(start -0.12065 -0.2794)
			(end -0.12065 -0.3048)
			(stroke
				(width 0.1)
				(type default)
			)
			(layer "B.Fab")
		)
		(fp_line
			(start 0.12065 0.2794)
			(end 0.12065 0.3048)
			(stroke
				(width 0.1)
				(type default)
			)
			(layer "B.Fab")
		)
		(fp_line
			(start -0.120396 0.2794)
			(end 0.12065 0.2794)
			(stroke
				(width 0.1)
				(type default)
			)
			(layer "B.Fab")
		)
		(fp_line
			(start 0.67945 0.3048)
			(end 0.67945 -0.305054)
			(stroke
				(width 0.1)
				(type default)
			)
			(layer "B.Fab")
		)
		(fp_line
			(start 0.12065 0.3048)
			(end 0.67945 0.3048)
			(stroke
				(width 0.1)
				(type default)
			)
			(layer "B.Fab")
		)
		(fp_line
			(start -0.120396 0.3048)
			(end -0.120396 0.2794)
			(stroke
				(width 0.1)
				(type default)
			)
			(layer "B.Fab")
		)
		(fp_line
			(start -0.67945 0.3048)
			(end -0.120396 0.3048)
			(stroke
				(width 0.1)
				(type default)
			)
			(layer "B.Fab")
		)
		(pad "1" smd circle
			(at 0.40005 0 270)
			(size 0 0)
			(layers "B.Cu" "B.Mask" "B.Paste")
			(net "FM_GPU_HSC_EN_BUF_R1")
		)
		(pad "2" smd circle
			(at -0.40005 0 270)
			(size 0 0)
			(layers "B.Cu" "B.Mask" "B.Paste")
			(net "GND")
		)
	)
	(footprint ""
		(layer "B.Cu")
		(at 163.387532 -434.15458 -90)
		(property "Reference" "R4121"
			(at 0 0 90)
			(layer "B.SilkS")
			(hide yes)
			(effects
				(font
					(size 1.27 1.27)
				)
				(justify mirror)
			)
		)
		(property "Value" ""
			(at 0 0 90)
			(layer "B.Fab")
			(effects
				(font
					(size 1.27 1.27)
				)
				(justify mirror)
			)
		)
		(duplicate_pad_numbers_are_jumpers no)
		(fp_line
			(start -0.7874 0.4064)
			(end 0.7874 0.4064)
			(stroke
				(width 0.1524)
				(type default)
			)
			(layer "B.SilkS")
		)
		(fp_line
			(start 0.7874 0.4064)
			(end 0.7874 -0.4064)
			(stroke
				(width 0.1524)
				(type default)
			)
			(layer "B.SilkS")
		)
		(fp_line
			(start -0.7874 -0.4064)
			(end -0.7874 0.4064)
			(stroke
				(width 0.1524)
				(type default)
			)
			(layer "B.SilkS")
		)
		(fp_line
			(start 0.7874 -0.4064)
			(end -0.7874 -0.4064)
			(stroke
				(width 0.1524)
				(type default)
			)
			(layer "B.SilkS")
		)
		(fp_line
			(start -0.67945 0.3048)
			(end -0.120396 0.3048)
			(stroke
				(width 0.1)
				(type default)
			)
			(layer "B.Fab")
		)
		(fp_line
			(start -0.120396 0.3048)
			(end -0.120396 0.2794)
			(stroke
				(width 0.1)
				(type default)
			)
			(layer "B.Fab")
		)
		(fp_line
			(start 0.12065 0.3048)
			(end 0.67945 0.3048)
			(stroke
				(width 0.1)
				(type default)
			)
			(layer "B.Fab")
		)
		(fp_line
			(start 0.67945 0.3048)
			(end 0.67945 -0.305054)
			(stroke
				(width 0.1)
				(type default)
			)
			(layer "B.Fab")
		)
		(fp_line
			(start -0.120396 0.2794)
			(end 0.12065 0.2794)
			(stroke
				(width 0.1)
				(type default)
			)
			(layer "B.Fab")
		)
		(fp_line
			(start 0.12065 0.2794)
			(end 0.12065 0.3048)
			(stroke
				(width 0.1)
				(type default)
			)
			(layer "B.Fab")
		)
		(fp_line
			(start -0.12065 -0.2794)
			(end -0.12065 -0.3048)
			(stroke
				(width 0.1)
				(type default)
			)
			(layer "B.Fab")
		)
		(fp_line
			(start 0.12065 -0.2794)
			(end -0.12065 -0.2794)
			(stroke
				(width 0.1)
				(type default)
			)
			(layer "B.Fab")
		)
		(fp_line
			(start -0.67945 -0.3048)
			(end -0.67945 0.3048)
			(stroke
				(width 0.1)
				(type default)
			)
			(layer "B.Fab")
		)
		(fp_line
			(start -0.12065 -0.3048)
			(end -0.67945 -0.3048)
			(stroke
				(width 0.1)
				(type default)
			)
			(layer "B.Fab")
		)
		(fp_line
			(start 0.12065 -0.305054)
			(end 0.12065 -0.2794)
			(stroke
				(width 0.1)
				(type default)
			)
			(layer "B.Fab")
		)
		(fp_line
			(start 0.67945 -0.305054)
			(end 0.12065 -0.305054)
			(stroke
				(width 0.1)
				(type default)
			)
			(layer "B.Fab")
		)
		(pad "1" smd circle
			(at 0.40005 0 90)
			(size 0 0)
			(layers "B.Cu" "B.Mask" "B.Paste")
			(net "P3V3_AUX")
		)
		(pad "2" smd circle
			(at -0.40005 0 90)
			(size 0 0)
			(layers "B.Cu" "B.Mask" "B.Paste")
			(net "PRSNT_CABLE_GPU_B3_N")
		)
	)
)
